# S9S_MB_2U (Grand Teton) — schematic netlist excerpt (pin names and nets, part order shuffled) for the footprints in the layout excerpt that follows; sources: Cadence DE-HDL packaged netlist, KiCad conversion of 03242023_DA0F0TMBIJ0_F0T_Motherboard_J_brd_V01_OCP.brd

R1527  Q_RES  1K 1% CHIP  pkg 0402LF  page 208 : A = FM_CLK_GEN1_OE0_N ; B = GND
R683  Q_RES  0 5% EMPTY  pkg 0402LF  page 229 : A = I3C_SPD_DDRABCD_CPU0_R_SDA ; B = I3C_SPD_DDRABCD_CPU0_LVC1_R_SDA

(kicad_pcb
	(version 20260206)
	(generator "pcbnew")
	(generator_version "10.0")
	(general
		(thickness 1.6)
		(legacy_teardrops no)
	)
	(paper "A4")
	(title_block
		(title "03242023_DA0F0TMBIJ0_F0T_Motherboard_J_brd_V01_OCP.brd")
		(comment 1 "Grand Teton / footprints 5121-5122 of 6105")
	)
	(layers
		(0 "F.Cu" signal "TOP")
		(4 "In1.Cu" signal "GND")
		(6 "In2.Cu" signal "IN1")
		(8 "In3.Cu" signal "GND1")
		(10 "In4.Cu" signal "IN2")
		(12 "In5.Cu" signal "GND2")
		(14 "In6.Cu" signal "IN3")
		(16 "In7.Cu" signal "GND3")
		(18 "In8.Cu" signal "VCC")
		(20 "In9.Cu" signal "VCC1")
		(22 "In10.Cu" signal "GND4")
		(24 "In11.Cu" signal "IN4")
		(26 "In12.Cu" signal "GND5")
		(28 "In13.Cu" signal "IN5")
		(30 "In14.Cu" signal "GND6")
		(32 "In15.Cu" signal "IN6")
		(34 "In16.Cu" signal "GND7")
		(2 "B.Cu" signal "BOTTOM")
		(9 "F.Adhes" user "F.Adhesive")
		(11 "B.Adhes" user "B.Adhesive")
		(13 "F.Paste" user "Package Geometry/Pastemask Top")
		(15 "B.Paste" user "Package Geometry/Pastemask Bottom")
		(5 "F.SilkS" user "Ref Des/Silkscreen Top")
		(7 "B.SilkS" user "Ref Des/Silkscreen Bottom")
		(1 "F.Mask" user "Board Geometry/Soldermask Top")
		(3 "B.Mask" user "Board Geometry/Soldermask Bottom")
		(17 "Dwgs.User" user "User.Drawings")
		(19 "Cmts.User" user "User.Comments")
		(21 "Eco1.User" user "User.Eco1")
		(23 "Eco2.User" user "User.Eco2")
		(25 "Edge.Cuts" user "Board Geometry/Outline")
		(27 "Margin" user)
		(31 "F.CrtYd" user "Package Geometry/Place Bound Top")
		(29 "B.CrtYd" user "Package Geometry/Place Bound Bottom")
		(35 "F.Fab" user "Ref Des/Assembly Top")
		(33 "B.Fab" user "Ref Des/Assembly Bottom")
	)
	(footprint ""
		(layer "B.Cu")
		(at 263.064752 -99.450398 -90)
		(property "Reference" "R1527"
			(at 0 0 90)
			(layer "B.SilkS")
			(hide yes)
			(effects
				(font
					(size 1.27 1.27)
				)
				(justify mirror)
			)
		)
		(property "Value" ""
			(at 0 0 90)
			(layer "B.Fab")
			(effects
				(font
					(size 1.27 1.27)
				)
				(justify mirror)
			)
		)
		(duplicate_pad_numbers_are_jumpers no)
		(fp_line
			(start -0.7874 0.4064)
			(end 0.7874 0.4064)
			(stroke
				(width 0.1524)
				(type default)
			)
			(layer "B.SilkS")
		)
		(fp_line
			(start 0.7874 0.4064)
			(end 0.7874 -0.4064)
			(stroke
				(width 0.1524)
				(type default)
			)
			(layer "B.SilkS")
		)
		(fp_line
			(start -0.7874 -0.4064)
			(end -0.7874 0.4064)
			(stroke
				(width 0.1524)
				(type default)
			)
			(layer "B.SilkS")
		)
		(fp_line
			(start 0.7874 -0.4064)
			(end -0.7874 -0.4064)
			(stroke
				(width 0.1524)
				(type default)
			)
			(layer "B.SilkS")
		)
		(fp_line
			(start -0.67945 0.3048)
			(end -0.120396 0.3048)
			(stroke
				(width 0.1)
				(type default)
			)
			(layer "B.Fab")
		)
		(fp_line
			(start -0.120396 0.3048)
			(end -0.120396 0.2794)
			(stroke
				(width 0.1)
				(type default)
			)
			(layer "B.Fab")
		)
		(fp_line
			(start 0.12065 0.3048)
			(end 0.67945 0.3048)
			(stroke
				(width 0.1)
				(type default)
			)
			(layer "B.Fab")
		)
		(fp_line
			(start 0.67945 0.3048)
			(end 0.67945 -0.305054)
			(stroke
				(width 0.1)
				(type default)
			)
			(layer "B.Fab")
		)
		(fp_line
			(start -0.120396 0.2794)
			(end 0.12065 0.2794)
			(stroke
				(width 0.1)
				(type default)
			)
			(layer "B.Fab")
		)
		(fp_line
			(start 0.12065 0.2794)
			(end 0.12065 0.3048)
			(stroke
				(width 0.1)
				(type default)
			)
			(layer "B.Fab")
		)
		(fp_line
			(start -0.12065 -0.2794)
			(end -0.12065 -0.3048)
			(stroke
				(width 0.1)
				(type default)
			)
			(layer "B.Fab")
		)
		(fp_line
			(start 0.12065 -0.2794)
			(end -0.12065 -0.2794)
			(stroke
				(width 0.1)
				(type default)
			)
			(layer "B.Fab")
		)
		(fp_line
			(start -0.67945 -0.3048)
			(end -0.67945 0.3048)
			(stroke
				(width 0.1)
				(type default)
			)
			(layer "B.Fab")
		)
		(fp_line
			(start -0.12065 -0.3048)
			(end -0.67945 -0.3048)
			(stroke
				(width 0.1)
				(type default)
			)
			(layer "B.Fab")
		)
		(fp_line
			(start 0.12065 -0.305054)
			(end 0.12065 -0.2794)
			(stroke
				(width 0.1)
				(type default)
			)
			(layer "B.Fab")
		)
		(fp_line
			(start 0.67945 -0.305054)
			(end 0.12065 -0.305054)
			(stroke
				(width 0.1)
				(type default)
			)
			(layer "B.Fab")
		)
		(pad "1" smd circle
			(at 0.40005 0 90)
			(size 0 0)
			(layers "B.Cu" "B.Mask" "B.Paste")
			(net "FM_CLK_GEN1_OE0_N")
		)
		(pad "2" smd circle
			(at -0.40005 0 90)
			(size 0 0)
			(layers "B.Cu" "B.Mask" "B.Paste")
			(net "GND")
		)
	)
	(footprint ""
		(layer "B.Cu")
		(at 292.998398 -153.546048 -90)
		(property "Reference" "R683"
			(at 0 0 90)
			(layer "B.SilkS")
			(hide yes)
			(effects
				(font
					(size 1.27 1.27)
				)
				(justify mirror)
			)
		)
		(property "Value" ""
			(at 0 0 90)
			(layer "B.Fab")
			(effects
				(font
					(size 1.27 1.27)
				)
				(justify mirror)
			)
		)
		(duplicate_pad_numbers_are_jumpers no)
		(fp_line
			(start -0.7874 0.4064)
			(end 0.7874 0.4064)
			(stroke
				(width 0.1524)
				(type default)
			)
			(layer "B.SilkS")
		)
		(fp_line
			(start 0.7874 0.4064)
			(end 0.7874 -0.4064)
			(stroke
				(width 0.1524)
				(type default)
			)
			(layer "B.SilkS")
		)
		(fp_line
			(start -0.7874 -0.4064)
			(end -0.7874 0.4064)
			(stroke
				(width 0.1524)
				(type default)
			)
			(layer "B.SilkS")
		)
		(fp_line
			(start 0.7874 -0.4064)
			(end -0.7874 -0.4064)
			(stroke
				(width 0.1524)
				(type default)
			)
			(layer "B.SilkS")
		)
		(fp_line
			(start -0.67945 0.3048)
			(end -0.120396 0.3048)
			(stroke
				(width 0.1)
				(type default)
			)
			(layer "B.Fab")
		)
		(fp_line
			(start -0.120396 0.3048)
			(end -0.120396 0.2794)
			(stroke
				(width 0.1)
				(type default)
			)
			(layer "B.Fab")
		)
		(fp_line
			(start 0.12065 0.3048)
			(end 0.67945 0.3048)
			(stroke
				(width 0.1)
				(type default)
			)
			(layer "B.Fab")
		)
		(fp_line
			(start 0.67945 0.3048)
			(end 0.67945 -0.305054)
			(stroke
				(width 0.1)
				(type default)
			)
			(layer "B.Fab")
		)
		(fp_line
			(start -0.120396 0.2794)
			(end 0.12065 0.2794)
			(stroke
				(width 0.1)
				(type default)
			)
			(layer "B.Fab")
		)
		(fp_line
			(start 0.12065 0.2794)
			(end 0.12065 0.3048)
			(stroke
				(width 0.1)
				(type default)
			)
			(layer "B.Fab")
		)
		(fp_line
			(start -0.12065 -0.2794)
			(end -0.12065 -0.3048)
			(stroke
				(width 0.1)
				(type default)
			)
			(layer "B.Fab")
		)
		(fp_line
			(start 0.12065 -0.2794)
			(end -0.12065 -0.2794)
			(stroke
				(width 0.1)
				(type default)
			)
			(layer "B.Fab")
		)
		(fp_line
			(start -0.67945 -0.3048)
			(end -0.67945 0.3048)
			(stroke
				(width 0.1)
				(type default)
			)
			(layer "B.Fab")
		)
		(fp_line
			(start -0.12065 -0.3048)
			(end -0.67945 -0.3048)
			(stroke
				(width 0.1)
				(type default)
			)
			(layer "B.Fab")
		)
		(fp_line
			(start 0.12065 -0.305054)
			(end 0.12065 -0.2794)
			(stroke
				(width 0.1)
				(type default)
			)
			(layer "B.Fab")
		)
		(fp_line
			(start 0.67945 -0.305054)
			(end 0.12065 -0.305054)
			(stroke
				(width 0.1)
				(type default)
			)
			(layer "B.Fab")
		)
		(pad "1" smd circle
			(at 0.40005 0 90)
			(size 0 0)
			(layers "B.Cu" "B.Mask" "B.Paste")
			(net "I3C_SPD_DDRABCD_CPU0_R_SDA")
		)
		(pad "2" smd circle
			(at -0.40005 0 90)
			(size 0 0)
			(layers "B.Cu" "B.Mask" "B.Paste")
			(net "I3C_SPD_DDRABCD_CPU0_LVC1_R_SDA")
		)
	)
)
